#ISCELL
  logical_power cad_note *
  *
#ISCELL
  mstr_misc dns *
  *
#ISCELL
  pure_quanta quanta_title_block_c *
  *
#ISCELL
  standard offpage *
  page209_i1
#ISCELL
  logical_power universal_gnd *
  page209_i10
#CELL
  pure_quanta q_res *
  page209_i11
#ISCELL
  logical_power universal_power *
  page209_i12
#CELL
  pure_quanta q_res *
  page209_i13
#CELL
  pure_quanta q_res *
  page209_i14
#CELL
  pure_quanta q_res *
  page209_i15
#CELL
  pure_quanta q_res *
  page209_i16
#CELL
  pure_quanta q_res *
  page209_i17
#ISCELL
  standard offpage *
  page209_i18
#ISCELL
  logical_power universal_power *
  page209_i19
#ISCELL
  standard offpage *
  page209_i2
#ISCELL
  logical_power universal_gnd *
  page209_i20
#CELL
  pure_quanta q_res *
  page209_i21
#CELL
  pure_quanta q_res *
  page209_i22
#CELL
  pure_quanta q_res *
  page209_i23
#CELL
  pure_quanta q_res *
  page209_i24
#ISCELL
  standard offpage *
  page209_i25
#ISCELL
  standard offpage *
  page209_i26
#ISCELL
  standard offpage *
  page209_i27
#ISCELL
  standard offpage *
  page209_i28
#ISCELL
  standard offpage *
  page209_i29
#CELL
  pure_quanta q_cap *
  page209_i3
#ISCELL
  standard offpage *
  page209_i30
#ISCELL
  standard offpage *
  page209_i31
#ISCELL
  standard offpage *
  page209_i32
#ISCELL
  standard offpage *
  page209_i33
#ISCELL
  standard offpage *
  page209_i34
#CELL
  pure_quanta q_res *
  page209_i35
#CELL
  pure_quanta q_res *
  page209_i36
#CELL
  pure_quanta q_res *
  page209_i37
#CELL
  pure_quanta q_res *
  page209_i38
#CELL
  pure_quanta q_res *
  page209_i39
#CELL
  pure_quanta q_cap *
  page209_i4
#CELL
  pure_quanta q_res *
  page209_i40
#CELL
  pure_quanta q_res *
  page209_i41
#CELL
  pure_quanta q_res *
  page209_i42
#CELL
  pure_quanta q_res *
  page209_i43
#CELL
  pure_quanta q_res *
  page209_i44
#ISCELL
  logical_power universal_power *
  page209_i45
#CELL
  pure_quanta q_res *
  page209_i46
#ISCELL
  logical_power universal_gnd *
  page209_i47
#ISCELL
  logical_power universal_gnd *
  page209_i5
#ISCELL
  standard offpage *
  page209_i6
#ISCELL
  standard offpage *
  page209_i7
#ISCELL
  standard offpage *
  page209_i8
#ISCELL
  standard offpage *
  page209_i9
